# S9S_MB_2U (Grand Teton) — schematic parts with pin connectivity, parts 1–148 of 6093; source: Cadence DE-HDL packaged netlist (pstxprt.dat, pstxnet.dat, pstchip.dat)

BT1  CONN2_AAABAT029Y19  CONN2_AAA-BAT-029-Y19 IO  pkg BATTERY_AAA-BAT-029-Y19  page 185 : 1 = P3V_BAT ; 2 = GND
C1  Q_CAP  10UF 6.3V 20% X6S  pkg C0402  page 37 : 1 = P3V3_AUX ; 2 = GND
C2  Q_CAP  2.2UF 6.3V 20% X6S  pkg C0402  page 82 : 1 = P3V3_AUX ; 2 = GND
C3  Q_CAP  10UF 16V 10% X6S  pkg C0805  page 82 : 1 = P12V_S3_AUX_CPU0_NVDIMM ; 2 = GND
C4  Q_CAP  10UF 16V 10% X6S  pkg C0805  page 82 : 1 = P12V_S3_AUX_CPU0_NVDIMM ; 2 = GND
C5  Q_CAP  2.2UF 6.3V 20% X6S  pkg C0402  page 83 : 1 = P3V3_AUX ; 2 = GND
C6  Q_CAP  10UF 16V 10% X6S  pkg C0805  page 83 : 1 = P12V_S3_AUX_CPU0_NVDIMM ; 2 = GND
C7  Q_CAP  10UF 16V 10% X6S  pkg C0805  page 83 : 1 = P12V_S3_AUX_CPU0_NVDIMM ; 2 = GND
C8  Q_CAP  2.2UF 6.3V 20% X6S  pkg C0402  page 84 : 1 = P3V3_AUX ; 2 = GND
C9  Q_CAP  10UF 16V 10% X6S  pkg C0805  page 84 : 1 = P12V_S3_AUX_CPU0_NVDIMM ; 2 = GND
C10  Q_CAP  10UF 16V 10% X6S  pkg C0805  page 84 : 1 = P12V_S3_AUX_CPU0_NVDIMM ; 2 = GND
C11  Q_CAP  2.2UF 6.3V 20% X6S  pkg C0402  page 85 : 1 = P3V3_AUX ; 2 = GND
C12  Q_CAP  10UF 16V 10% X6S  pkg C0805  page 85 : 1 = P12V_S3_AUX_CPU0_NVDIMM ; 2 = GND
C13  Q_CAP  10UF 16V 10% X6S  pkg C0805  page 85 : 1 = P12V_S3_AUX_CPU0_NVDIMM ; 2 = GND
C14  Q_CAP  2.2UF 6.3V 20% X6S  pkg C0402  page 86 : 1 = P3V3_AUX ; 2 = GND
C15  Q_CAP  10UF 16V 10% X6S  pkg C0805  page 86 : 1 = P12V_S3_AUX_CPU0_NVDIMM ; 2 = GND
C16  Q_CAP  10UF 16V 10% X6S  pkg C0805  page 86 : 1 = P12V_S3_AUX_CPU0_NVDIMM ; 2 = GND
C17  Q_CAP  2.2UF 6.3V 20% X6S  pkg C0402  page 87 : 1 = P3V3_AUX ; 2 = GND
C18  Q_CAP  10UF 16V 10% X6S  pkg C0805  page 87 : 1 = P12V_S3_AUX_CPU0_NVDIMM ; 2 = GND
C19  Q_CAP  10UF 16V 10% X6S  pkg C0805  page 87 : 1 = P12V_S3_AUX_CPU0_NVDIMM ; 2 = GND
C20  Q_CAP  2.2UF 6.3V 20% X6S  pkg C0402  page 88 : 1 = P3V3_AUX ; 2 = GND
C21  Q_CAP  10UF 16V 10% X6S  pkg C0805  page 88 : 1 = P12V_S3_AUX_CPU0_NVDIMM ; 2 = GND
C22  Q_CAP  10UF 16V 10% X6S  pkg C0805  page 88 : 1 = P12V_S3_AUX_CPU0_NVDIMM ; 2 = GND
C23  Q_CAP  2.2UF 6.3V 20% X6S  pkg C0402  page 89 : 1 = P3V3_AUX ; 2 = GND
C24  Q_CAP  10UF 16V 10% X6S  pkg C0805  page 89 : 1 = P12V_S3_AUX_CPU0_NVDIMM ; 2 = GND
C25  Q_CAP  10UF 16V 10% X6S  pkg C0805  page 89 : 1 = P12V_S3_AUX_CPU0_NVDIMM ; 2 = GND
C26  Q_CAP  2.2UF 6.3V 20% X6S  pkg C0402  page 90 : 1 = P3V3_AUX ; 2 = GND
C27  Q_CAP  10UF 16V 10% X6S  pkg C0805  page 90 : 1 = P12V_S3_AUX_CPU0_NVDIMM ; 2 = GND
C28  Q_CAP  10UF 16V 10% X6S  pkg C0805  page 90 : 1 = P12V_S3_AUX_CPU0_NVDIMM ; 2 = GND
C29  Q_CAP  2.2UF 6.3V 20% X6S  pkg C0402  page 91 : 1 = P3V3_AUX ; 2 = GND
C30  Q_CAP  10UF 16V 10% X6S  pkg C0805  page 91 : 1 = P12V_S3_AUX_CPU0_NVDIMM ; 2 = GND
C31  Q_CAP  10UF 16V 10% X6S  pkg C0805  page 91 : 1 = P12V_S3_AUX_CPU0_NVDIMM ; 2 = GND
C32  Q_CAP  2.2UF 6.3V 20% X6S  pkg C0402  page 92 : 1 = P3V3_AUX ; 2 = GND
C33  Q_CAP  10UF 16V 10% X6S  pkg C0805  page 92 : 1 = P12V_S3_AUX_CPU0_NVDIMM ; 2 = GND
C34  Q_CAP  10UF 16V 10% X6S  pkg C0805  page 92 : 1 = P12V_S3_AUX_CPU0_NVDIMM ; 2 = GND
C35  Q_CAP  2.2UF 6.3V 20% X6S  pkg C0402  page 93 : 1 = P3V3_AUX ; 2 = GND
C36  Q_CAP  10UF 16V 10% X6S  pkg C0805  page 93 : 1 = P12V_S3_AUX_CPU0_NVDIMM ; 2 = GND
C37  Q_CAP  10UF 16V 10% X6S  pkg C0805  page 93 : 1 = P12V_S3_AUX_CPU0_NVDIMM ; 2 = GND
C38  Q_CAP  2.2UF 6.3V 20% X6S  pkg C0402  page 94 : 1 = P3V3_AUX ; 2 = GND
C39  Q_CAP  10UF 16V 10% X6S  pkg C0805  page 94 : 1 = P12V_S3_AUX_CPU0_NVDIMM ; 2 = GND
C40  Q_CAP  10UF 16V 10% X6S  pkg C0805  page 94 : 1 = P12V_S3_AUX_CPU0_NVDIMM ; 2 = GND
C41  Q_CAP  2.2UF 6.3V 20% X6S  pkg C0402  page 95 : 1 = P3V3_AUX ; 2 = GND
C42  Q_CAP  10UF 16V 10% X6S  pkg C0805  page 95 : 1 = P12V_S3_AUX_CPU0_NVDIMM ; 2 = GND
C43  Q_CAP  10UF 16V 10% X6S  pkg C0805  page 95 : 1 = P12V_S3_AUX_CPU0_NVDIMM ; 2 = GND
C44  Q_CAP  2.2UF 6.3V 20% X6S  pkg C0402  page 96 : 1 = P3V3_AUX ; 2 = GND
C45  Q_CAP  10UF 16V 10% X6S  pkg C0805  page 96 : 1 = P12V_S3_AUX_CPU0_NVDIMM ; 2 = GND
C46  Q_CAP  10UF 16V 10% X6S  pkg C0805  page 96 : 1 = P12V_S3_AUX_CPU0_NVDIMM ; 2 = GND
C47  Q_CAP  2.2UF 6.3V 20% X6S  pkg C0402  page 97 : 1 = P3V3_AUX ; 2 = GND
C48  Q_CAP  10UF 16V 10% X6S  pkg C0805  page 97 : 1 = P12V_S3_AUX_CPU0_NVDIMM ; 2 = GND
C49  Q_CAP  10UF 16V 10% X6S  pkg C0805  page 97 : 1 = P12V_S3_AUX_CPU0_NVDIMM ; 2 = GND
C50  Q_CAP  2.2UF 6.3V 20% X6S  pkg C0402  page 98 : 1 = P3V3_AUX ; 2 = GND
C51  Q_CAP  10UF 16V 10% X6S  pkg C0805  page 98 : 1 = P12V_S3_AUX_CPU1_NVDIMM ; 2 = GND
C52  Q_CAP  10UF 16V 10% X6S  pkg C0805  page 98 : 1 = P12V_S3_AUX_CPU1_NVDIMM ; 2 = GND
C53  Q_CAP  2.2UF 6.3V 20% X6S  pkg C0402  page 99 : 1 = P3V3_AUX ; 2 = GND
C54  Q_CAP  10UF 16V 10% X6S  pkg C0805  page 99 : 1 = P12V_S3_AUX_CPU1_NVDIMM ; 2 = GND
C55  Q_CAP  10UF 16V 10% X6S  pkg C0805  page 99 : 1 = P12V_S3_AUX_CPU1_NVDIMM ; 2 = GND
C56  Q_CAP  2.2UF 6.3V 20% X6S  pkg C0402  page 100 : 1 = P3V3_AUX ; 2 = GND
C57  Q_CAP  10UF 16V 10% X6S  pkg C0805  page 100 : 1 = P12V_S3_AUX_CPU1_NVDIMM ; 2 = GND
C58  Q_CAP  10UF 16V 10% X6S  pkg C0805  page 100 : 1 = P12V_S3_AUX_CPU1_NVDIMM ; 2 = GND
C59  Q_CAP  2.2UF 6.3V 20% X6S  pkg C0402  page 101 : 1 = P3V3_AUX ; 2 = GND
C60  Q_CAP  10UF 16V 10% X6S  pkg C0805  page 101 : 1 = P12V_S3_AUX_CPU1_NVDIMM ; 2 = GND
C61  Q_CAP  10UF 16V 10% X6S  pkg C0805  page 101 : 1 = P12V_S3_AUX_CPU1_NVDIMM ; 2 = GND
C62  Q_CAP  2.2UF 6.3V 20% X6S  pkg C0402  page 102 : 1 = P3V3_AUX ; 2 = GND
C63  Q_CAP  10UF 16V 10% X6S  pkg C0805  page 102 : 1 = P12V_S3_AUX_CPU1_NVDIMM ; 2 = GND
C64  Q_CAP  10UF 16V 10% X6S  pkg C0805  page 102 : 1 = P12V_S3_AUX_CPU1_NVDIMM ; 2 = GND
C65  Q_CAP  2.2UF 6.3V 20% X6S  pkg C0402  page 103 : 1 = P3V3_AUX ; 2 = GND
C66  Q_CAP  10UF 16V 10% X6S  pkg C0805  page 103 : 1 = P12V_S3_AUX_CPU1_NVDIMM ; 2 = GND
C67  Q_CAP  10UF 16V 10% X6S  pkg C0805  page 103 : 1 = P12V_S3_AUX_CPU1_NVDIMM ; 2 = GND
C68  Q_CAP  2.2UF 6.3V 20% X6S  pkg C0402  page 104 : 1 = P3V3_AUX ; 2 = GND
C69  Q_CAP  10UF 16V 10% X6S  pkg C0805  page 104 : 1 = P12V_S3_AUX_CPU1_NVDIMM ; 2 = GND
C70  Q_CAP  10UF 16V 10% X6S  pkg C0805  page 104 : 1 = P12V_S3_AUX_CPU1_NVDIMM ; 2 = GND
C71  Q_CAP  10UF 6.3V 20% X6S  pkg C0402  page 68 : 1 = P3V3_AUX ; 2 = GND
C72  Q_CAP  2.2UF 6.3V 20% X6S  pkg C0402  page 113 : 1 = P3V3_AUX ; 2 = GND
C73  Q_CAP  10UF 16V 10% X6S  pkg C0805  page 113 : 1 = P12V_S3_AUX_CPU1_NVDIMM ; 2 = GND
C74  Q_CAP  10UF 16V 10% X6S  pkg C0805  page 113 : 1 = P12V_S3_AUX_CPU1_NVDIMM ; 2 = GND
C75  Q_CAP  2.2UF 6.3V 20% X6S  pkg C0402  page 112 : 1 = P3V3_AUX ; 2 = GND
C76  Q_CAP  10UF 16V 10% X6S  pkg C0805  page 112 : 1 = P12V_S3_AUX_CPU1_NVDIMM ; 2 = GND
C77  Q_CAP  10UF 16V 10% X6S  pkg C0805  page 112 : 1 = P12V_S3_AUX_CPU1_NVDIMM ; 2 = GND
C78  Q_CAP  2.2UF 6.3V 20% X6S  pkg C0402  page 111 : 1 = P3V3_AUX ; 2 = GND
C79  Q_CAP  10UF 16V 10% X6S  pkg C0805  page 111 : 1 = P12V_S3_AUX_CPU1_NVDIMM ; 2 = GND
C80  Q_CAP  10UF 16V 10% X6S  pkg C0805  page 111 : 1 = P12V_S3_AUX_CPU1_NVDIMM ; 2 = GND
C81  Q_CAP  2.2UF 6.3V 20% X6S  pkg C0402  page 110 : 1 = P3V3_AUX ; 2 = GND
C82  Q_CAP  10UF 16V 10% X6S  pkg C0805  page 110 : 1 = P12V_S3_AUX_CPU1_NVDIMM ; 2 = GND
C83  Q_CAP  10UF 16V 10% X6S  pkg C0805  page 110 : 1 = P12V_S3_AUX_CPU1_NVDIMM ; 2 = GND
C84  Q_CAP  2.2UF 6.3V 20% X6S  pkg C0402  page 109 : 1 = P3V3_AUX ; 2 = GND
C85  Q_CAP  10UF 16V 10% X6S  pkg C0805  page 109 : 1 = P12V_S3_AUX_CPU1_NVDIMM ; 2 = GND
C86  Q_CAP  10UF 16V 10% X6S  pkg C0805  page 109 : 1 = P12V_S3_AUX_CPU1_NVDIMM ; 2 = GND
C87  Q_CAP  2.2UF 6.3V 20% X6S  pkg C0402  page 108 : 1 = P3V3_AUX ; 2 = GND
C88  Q_CAP  10UF 16V 10% X6S  pkg C0805  page 108 : 1 = P12V_S3_AUX_CPU1_NVDIMM ; 2 = GND
C89  Q_CAP  10UF 16V 10% X6S  pkg C0805  page 108 : 1 = P12V_S3_AUX_CPU1_NVDIMM ; 2 = GND
C90  Q_CAP  2.2UF 6.3V 20% X6S  pkg C0402  page 107 : 1 = P3V3_AUX ; 2 = GND
C91  Q_CAP  10UF 16V 10% X6S  pkg C0805  page 107 : 1 = P12V_S3_AUX_CPU1_NVDIMM ; 2 = GND
C92  Q_CAP  10UF 16V 10% X6S  pkg C0805  page 107 : 1 = P12V_S3_AUX_CPU1_NVDIMM ; 2 = GND
C93  Q_CAP  2.2UF 6.3V 20% X6S  pkg C0402  page 106 : 1 = P3V3_AUX ; 2 = GND
C94  Q_CAP  10UF 16V 10% X6S  pkg C0805  page 106 : 1 = P12V_S3_AUX_CPU1_NVDIMM ; 2 = GND
C95  Q_CAP  10UF 16V 10% X6S  pkg C0805  page 106 : 1 = P12V_S3_AUX_CPU1_NVDIMM ; 2 = GND
C96  Q_CAP  2.2UF 6.3V 20% X6S  pkg C0402  page 105 : 1 = P3V3_AUX ; 2 = GND
C97  Q_CAP  10UF 16V 10% X6S  pkg C0805  page 105 : 1 = P12V_S3_AUX_CPU1_NVDIMM ; 2 = GND
C98  Q_CAP  10UF 16V 10% X6S  pkg C0805  page 105 : 1 = P12V_S3_AUX_CPU1_NVDIMM ; 2 = GND
C101  Q_CAP  47UF 4V 20% X6S  pkg C0805  page 74 : 1 = PVCCIN_CPU0 ; 2 = GND
C103  Q_CAP  27PF 50V 5% EMPTY  pkg 0402  page 179 : 1 = XTAL_PCH_25M_IN_R ; 2 = GND
C104  Q_CAP  27PF 50V 5% EMPTY  pkg 0402  page 179 : 1 = XTAL_PCH_25M_OUT ; 2 = GND
C107  Q_CAP  1UF 25V 10% X6S  pkg C0402  page 210 : 1 = P3V3_AUX_CLK_GEN_VDD_CK440 ; 2 = GND
C108  Q_CAP  10UF 6.3V 20% X6S  pkg C0603  page 210 : 1 = P3V3_AUX_CLK_GEN_VDD_CK440 ; 2 = GND
C110  Q_CAP  0.047UF 25V 10% X7R  pkg C0402  page 210 : 1 = P3V3_AUX_CLK_GEN_VDD_CK440 ; 2 = GND
C111  Q_CAP  0.047UF 25V 10% X7R  pkg C0402  page 210 : 1 = P3V3_AUX_CLK_GEN_VDDXTAL_CK440 ; 2 = GND
C112  Q_CAP  0.047UF 25V 10% X7R  pkg C0402  page 210 : 1 = P3V3_AUX_CLK_GEN_VDDXTAL_CK440 ; 2 = GND
C114  Q_CAP  0.047UF 25V 10% X7R  pkg C0402  page 210 : 1 = P3V3_AUX_CLK_GEN_VDDA25M_CK440 ; 2 = GND
C115  Q_CAP  0.047UF 25V 10% X7R  pkg C0402  page 210 : 1 = P3V3_AUX_CLK_GEN_VDDMXCK_CK440 ; 2 = GND
C116  Q_CAP  0.047UF 25V 10% X7R  pkg C0402  page 210 : 1 = P3V3_AUX_CLK_GEN_VDDMXCK_CK440 ; 2 = GND
C117  Q_CAP  0.047UF 25V 10% X7R  pkg C0402  page 210 : 1 = P3V3_AUX_CLK_GEN_VDDMXCK_CK440 ; 2 = GND
C119  Q_CAP  0.047UF 25V 10% X7R  pkg C0402  page 210 : 1 = P3V3_AUX_CLK_GEN_VDDMXCK_CK440 ; 2 = GND
C120  Q_CAP  0.047UF 25V 10% X7R  pkg C0402  page 210 : 1 = P3V3_AUX_CLK_GEN_VDDPT_CK440 ; 2 = GND
C139  Q_CAP_DIFFBUS  DIFF BUS_0.22UF 6.3V 20% X6S  pkg C0201  page 178 : 1 = DMI_CPU0_PCH_TX_C_DN<7> ; 2 = DMI_CPU0_PCH_TX_DN<7>
C141  Q_CAP_DIFFBUS  DIFF BUS_0.22UF 6.3V 20% X6S  pkg C0201  page 178 : 1 = DMI_CPU0_PCH_TX_C_DN<6> ; 2 = DMI_CPU0_PCH_TX_DN<6>
C142  Q_CAP_DIFFBUS  DIFF BUS_0.22UF 6.3V 20% X6S  pkg C0201  page 178 : 1 = DMI_CPU0_PCH_TX_C_DP<6> ; 2 = DMI_CPU0_PCH_TX_DP<6>
C143  Q_CAP_DIFFBUS  DIFF BUS_0.22UF 6.3V 20% X6S  pkg C0201  page 178 : 1 = DMI_CPU0_PCH_TX_C_DN<5> ; 2 = DMI_CPU0_PCH_TX_DN<5>
C144  Q_CAP_DIFFBUS  DIFF BUS_0.22UF 6.3V 20% X6S  pkg C0201  page 178 : 1 = DMI_CPU0_PCH_TX_C_DP<5> ; 2 = DMI_CPU0_PCH_TX_DP<5>
C145  Q_CAP_DIFFBUS  DIFF BUS_0.22UF 6.3V 20% X6S  pkg C0201  page 178 : 1 = DMI_CPU0_PCH_TX_C_DN<4> ; 2 = DMI_CPU0_PCH_TX_DN<4>
C146  Q_CAP_DIFFBUS  DIFF BUS_0.22UF 6.3V 20% X6S  pkg C0201  page 178 : 1 = DMI_CPU0_PCH_TX_C_DP<4> ; 2 = DMI_CPU0_PCH_TX_DP<4>
C147  Q_CAP_DIFFBUS  DIFF BUS_0.22UF 6.3V 20% X6S  pkg C0201  page 178 : 1 = DMI_CPU0_PCH_TX_C_DN<3> ; 2 = DMI_CPU0_PCH_TX_DN<3>
C148  Q_CAP_DIFFBUS  DIFF BUS_0.22UF 6.3V 20% X6S  pkg C0201  page 178 : 1 = DMI_CPU0_PCH_TX_C_DP<3> ; 2 = DMI_CPU0_PCH_TX_DP<3>
C149  Q_CAP_DIFFBUS  DIFF BUS_0.22UF 6.3V 20% X6S  pkg C0201  page 178 : 1 = DMI_CPU0_PCH_TX_C_DN<2> ; 2 = DMI_CPU0_PCH_TX_DN<2>
C150  Q_CAP_DIFFBUS  DIFF BUS_0.22UF 6.3V 20% X6S  pkg C0201  page 178 : 1 = DMI_CPU0_PCH_TX_C_DP<2> ; 2 = DMI_CPU0_PCH_TX_DP<2>
C151  Q_CAP_DIFFBUS  DIFF BUS_0.22UF 6.3V 20% X6S  pkg C0201  page 178 : 1 = DMI_CPU0_PCH_TX_C_DN<1> ; 2 = DMI_CPU0_PCH_TX_DN<1>
C152  Q_CAP_DIFFBUS  DIFF BUS_0.22UF 6.3V 20% X6S  pkg C0201  page 178 : 1 = DMI_CPU0_PCH_TX_C_DP<1> ; 2 = DMI_CPU0_PCH_TX_DP<1>
C153  Q_CAP_DIFFBUS  DIFF BUS_0.22UF 6.3V 20% X6S  pkg C0201  page 178 : 1 = DMI_CPU0_PCH_TX_C_DN<0> ; 2 = DMI_CPU0_PCH_TX_DN<0>
C154  Q_CAP_DIFFBUS  DIFF BUS_0.22UF 6.3V 20% X6S  pkg C0201  page 178 : 1 = DMI_CPU0_PCH_TX_C_DP<0> ; 2 = DMI_CPU0_PCH_TX_DP<0>
C155  Q_CAP_DIFFBUS  DIFF BUS_0.22UF 6.3V 20% X6S  pkg C0201  page 178 : 1 = DMI_CPU0_PCH_RX_C_DN<7> ; 2 = DMI_CPU0_PCH_RX_DN<7>
C156  Q_CAP_DIFFBUS  DIFF BUS_0.22UF 6.3V 20% X6S  pkg C0201  page 178 : 1 = DMI_CPU0_PCH_RX_C_DP<7> ; 2 = DMI_CPU0_PCH_RX_DP<7>
C157  Q_CAP_DIFFBUS  DIFF BUS_0.22UF 6.3V 20% X6S  pkg C0201  page 178 : 1 = DMI_CPU0_PCH_RX_C_DN<6> ; 2 = DMI_CPU0_PCH_RX_DN<6>
C158  Q_CAP_DIFFBUS  DIFF BUS_0.22UF 6.3V 20% X6S  pkg C0201  page 178 : 1 = DMI_CPU0_PCH_RX_C_DP<6> ; 2 = DMI_CPU0_PCH_RX_DP<6>
C159  Q_CAP_DIFFBUS  DIFF BUS_0.22UF 6.3V 20% X6S  pkg C0201  page 178 : 1 = DMI_CPU0_PCH_RX_C_DN<5> ; 2 = DMI_CPU0_PCH_RX_DN<5>
C160  Q_CAP_DIFFBUS  DIFF BUS_0.22UF 6.3V 20% X6S  pkg C0201  page 178 : 1 = DMI_CPU0_PCH_RX_C_DP<5> ; 2 = DMI_CPU0_PCH_RX_DP<5>
C161  Q_CAP_DIFFBUS  DIFF BUS_0.22UF 6.3V 20% X6S  pkg C0201  page 178 : 1 = DMI_CPU0_PCH_RX_C_DN<4> ; 2 = DMI_CPU0_PCH_RX_DN<4>
C162  Q_CAP_DIFFBUS  DIFF BUS_0.22UF 6.3V 20% X6S  pkg C0201  page 178 : 1 = DMI_CPU0_PCH_RX_C_DP<4> ; 2 = DMI_CPU0_PCH_RX_DP<4>
C163  Q_CAP_DIFFBUS  DIFF BUS_0.22UF 6.3V 20% X6S  pkg C0201  page 178 : 1 = DMI_CPU0_PCH_RX_C_DN<3> ; 2 = DMI_CPU0_PCH_RX_DN<3>
C164  Q_CAP_DIFFBUS  DIFF BUS_0.22UF 6.3V 20% X6S  pkg C0201  page 178 : 1 = DMI_CPU0_PCH_RX_C_DP<3> ; 2 = DMI_CPU0_PCH_RX_DP<3>
C165  Q_CAP_DIFFBUS  DIFF BUS_0.22UF 6.3V 20% X6S  pkg C0201  page 178 : 1 = DMI_CPU0_PCH_RX_C_DN<2> ; 2 = DMI_CPU0_PCH_RX_DN<2>
C166  Q_CAP_DIFFBUS  DIFF BUS_0.22UF 6.3V 20% X6S  pkg C0201  page 178 : 1 = DMI_CPU0_PCH_RX_C_DP<2> ; 2 = DMI_CPU0_PCH_RX_DP<2>
C167  Q_CAP_DIFFBUS  DIFF BUS_0.22UF 6.3V 20% X6S  pkg C0201  page 178 : 1 = DMI_CPU0_PCH_RX_C_DN<1> ; 2 = DMI_CPU0_PCH_RX_DN<1>
C168  Q_CAP_DIFFBUS  DIFF BUS_0.22UF 6.3V 20% X6S  pkg C0201  page 178 : 1 = DMI_CPU0_PCH_RX_C_DP<1> ; 2 = DMI_CPU0_PCH_RX_DP<1>
C169  Q_CAP_DIFFBUS  DIFF BUS_0.22UF 6.3V 20% X6S  pkg C0201  page 178 : 1 = DMI_CPU0_PCH_RX_C_DN<0> ; 2 = DMI_CPU0_PCH_RX_DN<0>
C170  Q_CAP_DIFFBUS  DIFF BUS_0.22UF 6.3V 20% X6S  pkg C0201  page 178 : 1 = DMI_CPU0_PCH_RX_C_DP<0> ; 2 = DMI_CPU0_PCH_RX_DP<0>
C171  Q_CAP  0.047UF 25V 10% X7R  pkg C0402  page 210 : 1 = P3V3_AUX_CLK_GEN_VDD_CK440 ; 2 = GND
C172  Q_CAP  10UF 6.3V 20% X6S  pkg C0603  page 210 : 1 = P3V3_AUX_CLK_GEN_VDDA100M_CK440 ; 2 = GND
C173  Q_CAP  0.047UF 25V 10% X7R  pkg C0402  page 210 : 1 = P3V3_AUX_CLK_GEN_VDDA100M_CK440 ; 2 = GND
C174  Q_CAP  0.1UF 25V 10% X7R  pkg 0402  page 231 : 1 = P3V3_AUX ; 2 = GND
